FILE_TYPE = MACRO_DRAWING;
SET COLOR_WIRE YELLOW;
SET COLOR_PROP MONO;
SET COLOR_DOT WHITE;
SET COLOR_ARC YELLOW;
SET COLOR_BODY GREEN;
SET COLOR_NOTE MONO;
SET PROP_DISPLAY VALUE;
SET PAGE_NUMBER P36;
FORCEADD VCC_CORE..1
(-4500 3800);
FORCEPROP 3 LASTPIN (-4500 3750) SIG_NAME PVCCMCP_CPU0\g
J 0
(-4490 3760);
DISPLAY 0.659574 (-4490 3760);
PAINT MONO (-4490 3760);
DISPLAY INVISIBLE (-4490 3760);
FORCEPROP 1 LAST HDL_POWER PVCCMCP_CPU0
J 1
(-4500 3850);
DISPLAY 0.617021 (-4500 3850);
PAINT GREEN (-4500 3850);
FORCEPROP 2 LAST CDS_LIB mstr_symbols
J 0
(-4500 3800);
PAINT ORANGE (-4500 3800);
DISPLAY INVISIBLE (-4500 3800);
FORCEPROP 1 LAST PATH I12
J 0
(-4450 3825);
DISPLAY 0.872340 (-4450 3825);
PAINT AQUA (-4450 3825);
DISPLAY INVISIBLE (-4450 3825);
FORCEADD VCC_CORE..1
(-925 2700);
FORCEPROP 3 LASTPIN (-925 2650) SIG_NAME PVCCMCP_CPU0\g
J 0
(-915 2660);
DISPLAY 0.659574 (-915 2660);
PAINT MONO (-915 2660);
DISPLAY INVISIBLE (-915 2660);
FORCEPROP 1 LAST HDL_POWER PVCCMCP_CPU0
J 1
(-925 2750);
DISPLAY 0.617021 (-925 2750);
PAINT GREEN (-925 2750);
FORCEPROP 2 LAST CDS_LIB mstr_symbols
J 0
(-925 2700);
PAINT ORANGE (-925 2700);
DISPLAY INVISIBLE (-925 2700);
FORCEPROP 1 LAST PATH I13
J 0
(-875 2725);
DISPLAY 0.872340 (-875 2725);
PAINT AQUA (-875 2725);
DISPLAY INVISIBLE (-875 2725);
FORCEADD VCC_CORE..1
(-7850 2350);
FORCEPROP 3 LASTPIN (-7850 2300) SIG_NAME PVCCMCP_CPU0\g
J 0
(-7840 2310);
DISPLAY 0.659574 (-7840 2310);
PAINT MONO (-7840 2310);
DISPLAY INVISIBLE (-7840 2310);
FORCEPROP 1 LAST HDL_POWER PVCCMCP_CPU0
J 1
(-7850 2400);
DISPLAY 0.617021 (-7850 2400);
PAINT GREEN (-7850 2400);
FORCEPROP 2 LAST CDS_LIB mstr_symbols
J 0
(-7850 2350);
PAINT ORANGE (-7850 2350);
DISPLAY INVISIBLE (-7850 2350);
FORCEPROP 1 LAST PATH I14
J 0
(-7800 2375);
DISPLAY 0.872340 (-7800 2375);
PAINT AQUA (-7800 2375);
DISPLAY INVISIBLE (-7800 2375);
FORCEADD SKX_EXT_B..16
(-6075 2550);
FORCEPROP 1 LAST LOCATION U5D1
J 0
(-6625 3900);
DISPLAY 0.617021 (-6625 3900);
PAINT AQUA (-6625 3900);
FORCEPROP 1 LAST PART_NUMBER TBD
J 0
(-6625 1250);
DISPLAY 0.617021 (-6625 1250);
PAINT BLUE (-6625 1250);
FORCEPROP 1 LAST MATERIAL IC
J 0
(-6625 3850);
DISPLAY 0.617021 (-6625 3850);
PAINT SKYBLUE (-6625 3850);
FORCEPROP 2 LASTPIN (-5475 1900) $PN AY83
J 0
(-5465 1910);
DISPLAY 0.617021 (-5465 1910);
PAINT ORANGE (-5465 1910);
FORCEPROP 2 LASTPIN (-6675 3650) $PN BA78
J 2
(-6685 3660);
DISPLAY 0.617021 (-6685 3660);
PAINT ORANGE (-6685 3660);
FORCEPROP 2 LASTPIN (-6675 3600) $PN BA82
J 2
(-6685 3610);
DISPLAY 0.617021 (-6685 3610);
PAINT ORANGE (-6685 3610);
FORCEPROP 2 LASTPIN (-6675 3550) $PN BB13
J 2
(-6685 3560);
DISPLAY 0.617021 (-6685 3560);
PAINT ORANGE (-6685 3560);
FORCEPROP 2 LASTPIN (-6675 3500) $PN BB15
J 2
(-6685 3510);
DISPLAY 0.617021 (-6685 3510);
PAINT ORANGE (-6685 3510);
FORCEPROP 2 LASTPIN (-6675 3450) $PN BB17
J 2
(-6685 3460);
DISPLAY 0.617021 (-6685 3460);
PAINT ORANGE (-6685 3460);
FORCEPROP 2 LASTPIN (-6675 3400) $PN BB21
J 2
(-6685 3410);
DISPLAY 0.617021 (-6685 3410);
PAINT ORANGE (-6685 3410);
FORCEPROP 2 LASTPIN (-6675 3350) $PN BB25
J 2
(-6685 3360);
DISPLAY 0.617021 (-6685 3360);
PAINT ORANGE (-6685 3360);
FORCEPROP 2 LASTPIN (-6675 3300) $PN BB65
J 2
(-6685 3310);
DISPLAY 0.617021 (-6685 3310);
PAINT ORANGE (-6685 3310);
FORCEPROP 2 LASTPIN (-6675 3250) $PN BB67
J 2
(-6685 3260);
DISPLAY 0.617021 (-6685 3260);
PAINT ORANGE (-6685 3260);
FORCEPROP 2 LASTPIN (-6675 3200) $PN BC14
J 2
(-6685 3210);
DISPLAY 0.617021 (-6685 3210);
PAINT ORANGE (-6685 3210);
FORCEPROP 2 LASTPIN (-6675 3150) $PN BC18
J 2
(-6685 3160);
DISPLAY 0.617021 (-6685 3160);
PAINT ORANGE (-6685 3160);
FORCEPROP 2 LASTPIN (-6675 3100) $PN BC20
J 2
(-6685 3110);
DISPLAY 0.617021 (-6685 3110);
PAINT ORANGE (-6685 3110);
FORCEPROP 2 LASTPIN (-6675 3050) $PN BC22
J 2
(-6685 3060);
DISPLAY 0.617021 (-6685 3060);
PAINT ORANGE (-6685 3060);
FORCEPROP 2 LASTPIN (-6675 3000) $PN BC64
J 2
(-6685 3010);
DISPLAY 0.617021 (-6685 3010);
PAINT ORANGE (-6685 3010);
FORCEPROP 2 LASTPIN (-6675 2950) $PN BC66
J 2
(-6685 2960);
DISPLAY 0.617021 (-6685 2960);
PAINT ORANGE (-6685 2960);
FORCEPROP 2 LASTPIN (-6675 2900) $PN BC68
J 2
(-6685 2910);
DISPLAY 0.617021 (-6685 2910);
PAINT ORANGE (-6685 2910);
FORCEPROP 2 LASTPIN (-6675 2850) $PN BD17
J 2
(-6685 2860);
DISPLAY 0.617021 (-6685 2860);
PAINT ORANGE (-6685 2860);
FORCEPROP 2 LASTPIN (-6675 2800) $PN BD19
J 2
(-6685 2810);
DISPLAY 0.617021 (-6685 2810);
PAINT ORANGE (-6685 2810);
FORCEPROP 2 LASTPIN (-6675 2750) $PN BD25
J 2
(-6685 2760);
DISPLAY 0.617021 (-6685 2760);
PAINT ORANGE (-6685 2760);
FORCEPROP 2 LASTPIN (-6675 2700) $PN BD65
J 2
(-6685 2710);
DISPLAY 0.617021 (-6685 2710);
PAINT ORANGE (-6685 2710);
FORCEPROP 2 LASTPIN (-6675 2650) $PN BD67
J 2
(-6685 2660);
DISPLAY 0.617021 (-6685 2660);
PAINT ORANGE (-6685 2660);
FORCEPROP 2 LASTPIN (-6675 2600) $PN BD69
J 2
(-6685 2610);
DISPLAY 0.617021 (-6685 2610);
PAINT ORANGE (-6685 2610);
FORCEPROP 2 LASTPIN (-6675 2550) $PN BE18
J 2
(-6685 2560);
DISPLAY 0.617021 (-6685 2560);
PAINT ORANGE (-6685 2560);
FORCEPROP 2 LASTPIN (-6675 2500) $PN BE20
J 2
(-6685 2510);
DISPLAY 0.617021 (-6685 2510);
PAINT ORANGE (-6685 2510);
FORCEPROP 2 LASTPIN (-6675 2450) $PN BE22
J 2
(-6685 2460);
DISPLAY 0.617021 (-6685 2460);
PAINT ORANGE (-6685 2460);
FORCEPROP 2 LASTPIN (-6675 2400) $PN BF21
J 2
(-6685 2410);
DISPLAY 0.617021 (-6685 2410);
PAINT ORANGE (-6685 2410);
FORCEPROP 2 LASTPIN (-6675 2350) $PN BG18
J 2
(-6685 2360);
DISPLAY 0.617021 (-6685 2360);
PAINT ORANGE (-6685 2360);
FORCEPROP 2 LASTPIN (-6675 2300) $PN BG20
J 2
(-6685 2310);
DISPLAY 0.617021 (-6685 2310);
PAINT ORANGE (-6685 2310);
FORCEPROP 2 LASTPIN (-6675 2250) $PN BH19
J 2
(-6685 2260);
DISPLAY 0.617021 (-6685 2260);
PAINT ORANGE (-6685 2260);
FORCEPROP 2 LASTPIN (-6675 2200) $PN BJ16
J 2
(-6685 2210);
DISPLAY 0.617021 (-6685 2210);
PAINT ORANGE (-6685 2210);
FORCEPROP 2 LASTPIN (-6675 2150) $PN BJ18
J 2
(-6685 2160);
DISPLAY 0.617021 (-6685 2160);
PAINT ORANGE (-6685 2160);
FORCEPROP 2 LASTPIN (-6675 2100) $PN BJ20
J 2
(-6685 2110);
DISPLAY 0.617021 (-6685 2110);
PAINT ORANGE (-6685 2110);
FORCEPROP 2 LASTPIN (-6675 2050) $PN BK17
J 2
(-6685 2060);
DISPLAY 0.617021 (-6685 2060);
PAINT ORANGE (-6685 2060);
FORCEPROP 2 LASTPIN (-6675 2000) $PN BL18
J 2
(-6685 2010);
DISPLAY 0.617021 (-6685 2010);
PAINT ORANGE (-6685 2010);
FORCEPROP 2 LASTPIN (-6675 1950) $PN BL20
J 2
(-6685 1960);
DISPLAY 0.617021 (-6685 1960);
PAINT ORANGE (-6685 1960);
FORCEPROP 2 LASTPIN (-6675 1900) $PN BM17
J 2
(-6685 1910);
DISPLAY 0.617021 (-6685 1910);
PAINT ORANGE (-6685 1910);
FORCEPROP 2 LASTPIN (-6675 1850) $PN BM19
J 2
(-6685 1860);
DISPLAY 0.617021 (-6685 1860);
PAINT ORANGE (-6685 1860);
FORCEPROP 2 LASTPIN (-6675 1800) $PN BN18
J 2
(-6685 1810);
DISPLAY 0.617021 (-6685 1810);
PAINT ORANGE (-6685 1810);
FORCEPROP 2 LASTPIN (-6675 1750) $PN BP17
J 2
(-6685 1760);
DISPLAY 0.617021 (-6685 1760);
PAINT ORANGE (-6685 1760);
FORCEPROP 2 LASTPIN (-6675 1700) $PN BP21
J 2
(-6685 1710);
DISPLAY 0.617021 (-6685 1710);
PAINT ORANGE (-6685 1710);
FORCEPROP 2 LASTPIN (-6675 1650) $PN BR22
J 2
(-6685 1660);
DISPLAY 0.617021 (-6685 1660);
PAINT ORANGE (-6685 1660);
FORCEPROP 2 LASTPIN (-6675 1600) $PN BR24
J 2
(-6685 1610);
DISPLAY 0.617021 (-6685 1610);
PAINT ORANGE (-6685 1610);
FORCEPROP 2 LASTPIN (-6675 1550) $PN BU18
J 2
(-6685 1560);
DISPLAY 0.617021 (-6685 1560);
PAINT ORANGE (-6685 1560);
FORCEPROP 2 LASTPIN (-6675 1500) $PN BU20
J 2
(-6685 1510);
DISPLAY 0.617021 (-6685 1510);
PAINT ORANGE (-6685 1510);
FORCEPROP 2 LASTPIN (-6675 1450) $PN BU22
J 2
(-6685 1460);
DISPLAY 0.617021 (-6685 1460);
PAINT ORANGE (-6685 1460);
FORCEPROP 2 LASTPIN (-5475 3650) $PN BV19
J 0
(-5465 3660);
DISPLAY 0.617021 (-5465 3660);
PAINT ORANGE (-5465 3660);
FORCEPROP 2 LASTPIN (-5475 3600) $PN BV21
J 0
(-5465 3610);
DISPLAY 0.617021 (-5465 3610);
PAINT ORANGE (-5465 3610);
FORCEPROP 2 LASTPIN (-5475 3550) $PN BV23
J 0
(-5465 3560);
DISPLAY 0.617021 (-5465 3560);
PAINT ORANGE (-5465 3560);
FORCEPROP 2 LASTPIN (-5475 3500) $PN BW10
J 0
(-5465 3510);
DISPLAY 0.617021 (-5465 3510);
PAINT ORANGE (-5465 3510);
FORCEPROP 2 LASTPIN (-5475 3450) $PN BW20
J 0
(-5465 3460);
DISPLAY 0.617021 (-5465 3460);
PAINT ORANGE (-5465 3460);
FORCEPROP 2 LASTPIN (-5475 3400) $PN BW22
J 0
(-5465 3410);
DISPLAY 0.617021 (-5465 3410);
PAINT ORANGE (-5465 3410);
FORCEPROP 2 LASTPIN (-5475 3350) $PN BY19
J 0
(-5465 3360);
DISPLAY 0.617021 (-5465 3360);
PAINT ORANGE (-5465 3360);
FORCEPROP 2 LASTPIN (-5475 3300) $PN BY25
J 0
(-5465 3310);
DISPLAY 0.617021 (-5465 3310);
PAINT ORANGE (-5465 3310);
FORCEPROP 2 LASTPIN (-5475 3250) $PN CA22
J 0
(-5465 3260);
DISPLAY 0.617021 (-5465 3260);
PAINT ORANGE (-5465 3260);
FORCEPROP 2 LASTPIN (-5475 3200) $PN CA24
J 0
(-5465 3210);
DISPLAY 0.617021 (-5465 3210);
PAINT ORANGE (-5465 3210);
FORCEPROP 2 LASTPIN (-5475 3150) $PN CB19
J 0
(-5465 3160);
DISPLAY 0.617021 (-5465 3160);
PAINT ORANGE (-5465 3160);
FORCEPROP 2 LASTPIN (-5475 3100) $PN CB21
J 0
(-5465 3110);
DISPLAY 0.617021 (-5465 3110);
PAINT ORANGE (-5465 3110);
FORCEPROP 2 LASTPIN (-5475 3050) $PN CB25
J 0
(-5465 3060);
DISPLAY 0.617021 (-5465 3060);
PAINT ORANGE (-5465 3060);
FORCEPROP 2 LASTPIN (-5475 3000) $PN CB5
J 0
(-5465 3010);
DISPLAY 0.617021 (-5465 3010);
PAINT ORANGE (-5465 3010);
FORCEPROP 2 LASTPIN (-5475 2950) $PN CC20
J 0
(-5465 2960);
DISPLAY 0.617021 (-5465 2960);
PAINT ORANGE (-5465 2960);
FORCEPROP 2 LASTPIN (-5475 2900) $PN CC6
J 0
(-5465 2910);
DISPLAY 0.617021 (-5465 2910);
PAINT ORANGE (-5465 2910);
FORCEPROP 2 LASTPIN (-5475 2850) $PN CD19
J 0
(-5465 2860);
DISPLAY 0.617021 (-5465 2860);
PAINT ORANGE (-5465 2860);
FORCEPROP 2 LASTPIN (-5475 2800) $PN CD21
J 0
(-5465 2810);
DISPLAY 0.617021 (-5465 2810);
PAINT ORANGE (-5465 2810);
FORCEPROP 2 LASTPIN (-5475 2750) $PN CD25
J 0
(-5465 2760);
DISPLAY 0.617021 (-5465 2760);
PAINT ORANGE (-5465 2760);
FORCEPROP 2 LASTPIN (-5475 2700) $PN CE22
J 0
(-5465 2710);
DISPLAY 0.617021 (-5465 2710);
PAINT ORANGE (-5465 2710);
FORCEPROP 2 LASTPIN (-5475 2650) $PN CE78
J 0
(-5465 2660);
DISPLAY 0.617021 (-5465 2660);
PAINT ORANGE (-5465 2660);
FORCEPROP 2 LASTPIN (-5475 2600) $PN CE80
J 0
(-5465 2610);
DISPLAY 0.617021 (-5465 2610);
PAINT ORANGE (-5465 2610);
FORCEPROP 2 LASTPIN (-5475 2550) $PN CF19
J 0
(-5465 2560);
DISPLAY 0.617021 (-5465 2560);
PAINT ORANGE (-5465 2560);
FORCEPROP 2 LASTPIN (-5475 2500) $PN CF21
J 0
(-5465 2510);
DISPLAY 0.617021 (-5465 2510);
PAINT ORANGE (-5465 2510);
FORCEPROP 2 LASTPIN (-5475 2450) $PN CF23
J 0
(-5465 2460);
DISPLAY 0.617021 (-5465 2460);
PAINT ORANGE (-5465 2460);
FORCEPROP 2 LASTPIN (-5475 2400) $PN CF79
J 0
(-5465 2410);
DISPLAY 0.617021 (-5465 2410);
PAINT ORANGE (-5465 2410);
FORCEPROP 2 LASTPIN (-5475 2350) $PN CF81
J 0
(-5465 2360);
DISPLAY 0.617021 (-5465 2360);
PAINT ORANGE (-5465 2360);
FORCEPROP 2 LASTPIN (-5475 2300) $PN CG10
J 0
(-5465 2310);
DISPLAY 0.617021 (-5465 2310);
PAINT ORANGE (-5465 2310);
FORCEPROP 2 LASTPIN (-5475 2250) $PN CG20
J 0
(-5465 2260);
DISPLAY 0.617021 (-5465 2260);
PAINT ORANGE (-5465 2260);
FORCEPROP 2 LASTPIN (-5475 2200) $PN CG24
J 0
(-5465 2210);
DISPLAY 0.617021 (-5465 2210);
PAINT ORANGE (-5465 2210);
FORCEPROP 2 LASTPIN (-5475 2150) $PN CG26
J 0
(-5465 2160);
DISPLAY 0.617021 (-5465 2160);
PAINT ORANGE (-5465 2160);
FORCEPROP 2 LASTPIN (-5475 2100) $PN CG78
J 0
(-5465 2110);
DISPLAY 0.617021 (-5465 2110);
PAINT ORANGE (-5465 2110);
FORCEPROP 2 LASTPIN (-5475 2050) $PN CG82
J 0
(-5465 2060);
DISPLAY 0.617021 (-5465 2060);
PAINT ORANGE (-5465 2060);
FORCEPROP 2 LASTPIN (-5475 2000) $PN CH21
J 0
(-5465 2010);
DISPLAY 0.617021 (-5465 2010);
PAINT ORANGE (-5465 2010);
FORCEPROP 2 LASTPIN (-5475 1950) $PN CH23
J 0
(-5465 1960);
DISPLAY 0.617021 (-5465 1960);
PAINT ORANGE (-5465 1960);
FORCEPROP 1 LAST PACK_TYPE BGA1
J 0
(-6625 3950);
PAINT SKYBLUE (-6625 3950);
DISPLAY INVISIBLE (-6625 3950);
FORCEPROP 2 LAST SEC_TYPE BGA1
J 0
(-6625 3950);
DISPLAY 1.021277 (-6625 3950);
PAINT ORANGE (-6625 3950);
DISPLAY INVISIBLE (-6625 3950);
FORCEPROP 2 LAST CDS_LIB chpset_lib
J 0
(-6075 2550);
PAINT ORANGE (-6075 2550);
DISPLAY INVISIBLE (-6075 2550);
FORCEPROP 2 LAST SEC 16
J 0
(-6625 3950);
DISPLAY 0.680851 (-6625 3950);
PAINT MONO (-6625 3950);
DISPLAY INVISIBLE (-6625 3950);
FORCEPROP 2 LAST CDS_LOCATION U5D1
J 0
(-6625 3900);
DISPLAY 0.617021 (-6625 3900);
PAINT AQUA (-6625 3900);
DISPLAY INVISIBLE (-6625 3900);
FORCEPROP 1 LAST PATH I15
J 0
(-6075 3850);
PAINT GREEN (-6075 3850);
DISPLAY INVISIBLE (-6075 3850);
FORCEPROP 0 LAST ROOM CPU0
J 0
(-6625 4000);
DISPLAY 1.021277 (-6625 4000);
PAINT ORANGE (-6625 4000);
DISPLAY INVISIBLE (-6625 4000);
FORCEADD SKX_EXT_B..17
(-2550 2525);
FORCEPROP 1 LAST LOCATION U5D1
J 0
(-3200 3275);
DISPLAY 0.617021 (-3200 3275);
PAINT AQUA (-3200 3275);
FORCEPROP 1 LAST PART_NUMBER TBD
J 0
(-3200 1975);
DISPLAY 0.617021 (-3200 1975);
PAINT BLUE (-3200 1975);
FORCEPROP 1 LAST MATERIAL IC
J 0
(-3200 3225);
DISPLAY 0.617021 (-3200 3225);
PAINT SKYBLUE (-3200 3225);
FORCEPROP 2 LASTPIN (-1850 2825) $PN AW22
J 0
(-1840 2835);
DISPLAY 0.617021 (-1840 2835);
PAINT ORANGE (-1840 2835);
FORCEPROP 2 LASTPIN (-1850 2875) $PN AW20
J 0
(-1840 2885);
DISPLAY 0.617021 (-1840 2885);
PAINT ORANGE (-1840 2885);
FORCEPROP 2 LASTPIN (-1850 2925) $PN AW16
J 0
(-1840 2935);
DISPLAY 0.617021 (-1840 2935);
PAINT ORANGE (-1840 2935);
FORCEPROP 2 LASTPIN (-1850 2975) $PN AU18
J 0
(-1840 2985);
DISPLAY 0.617021 (-1840 2985);
PAINT ORANGE (-1840 2985);
FORCEPROP 2 LASTPIN (-1850 3025) $PN AR16
J 0
(-1840 3035);
DISPLAY 0.617021 (-1840 3035);
PAINT ORANGE (-1840 3035);
FORCEPROP 2 LASTPIN (-1850 2725) $PN CH25
J 0
(-1840 2735);
DISPLAY 0.617021 (-1840 2735);
PAINT ORANGE (-1840 2735);
FORCEPROP 2 LASTPIN (-1850 2675) $PN CH77
J 0
(-1840 2685);
DISPLAY 0.617021 (-1840 2685);
PAINT ORANGE (-1840 2685);
FORCEPROP 2 LASTPIN (-1850 2575) $PN CJ20
J 0
(-1840 2585);
DISPLAY 0.617021 (-1840 2585);
PAINT ORANGE (-1840 2585);
FORCEPROP 2 LASTPIN (-1850 2525) $PN CJ22
J 0
(-1840 2535);
DISPLAY 0.617021 (-1840 2535);
PAINT ORANGE (-1840 2535);
FORCEPROP 2 LASTPIN (-1850 2475) $PN CJ24
J 0
(-1840 2485);
DISPLAY 0.617021 (-1840 2485);
PAINT ORANGE (-1840 2485);
FORCEPROP 2 LASTPIN (-1850 2425) $PN CJ26
J 0
(-1840 2435);
DISPLAY 0.617021 (-1840 2435);
PAINT ORANGE (-1840 2435);
FORCEPROP 2 LASTPIN (-1850 2375) $PN CK19
J 0
(-1840 2385);
DISPLAY 0.617021 (-1840 2385);
PAINT ORANGE (-1840 2385);
FORCEPROP 2 LASTPIN (-1850 2325) $PN CK23
J 0
(-1840 2335);
DISPLAY 0.617021 (-1840 2335);
PAINT ORANGE (-1840 2335);
FORCEPROP 2 LASTPIN (-1850 2275) $PN CK25
J 0
(-1840 2285);
DISPLAY 0.617021 (-1840 2285);
PAINT ORANGE (-1840 2285);
FORCEPROP 2 LASTPIN (-1850 2225) $PN CK77
J 0
(-1840 2235);
DISPLAY 0.617021 (-1840 2235);
PAINT ORANGE (-1840 2235);
FORCEPROP 2 LASTPIN (-1850 2175) $PN CL24
J 0
(-1840 2185);
DISPLAY 0.617021 (-1840 2185);
PAINT ORANGE (-1840 2185);
FORCEPROP 1 LAST PACK_TYPE BGA1
J 0
(-3200 3325);
PAINT SKYBLUE (-3200 3325);
DISPLAY INVISIBLE (-3200 3325);
FORCEPROP 2 LAST SEC_TYPE BGA1
J 0
(-3200 3325);
DISPLAY 1.021277 (-3200 3325);
PAINT ORANGE (-3200 3325);
DISPLAY INVISIBLE (-3200 3325);
FORCEPROP 2 LAST CDS_LIB chpset_lib
J 0
(-2550 2525);
PAINT ORANGE (-2550 2525);
DISPLAY INVISIBLE (-2550 2525);
FORCEPROP 2 LAST SEC 17
J 0
(-3200 3325);
DISPLAY 0.680851 (-3200 3325);
PAINT MONO (-3200 3325);
DISPLAY INVISIBLE (-3200 3325);
FORCEPROP 2 LAST CDS_LOCATION U5D1
J 0
(-3200 3275);
DISPLAY 0.617021 (-3200 3275);
PAINT AQUA (-3200 3275);
DISPLAY INVISIBLE (-3200 3275);
FORCEPROP 1 LAST PATH I16
J 0
(-2550 3225);
PAINT GREEN (-2550 3225);
DISPLAY INVISIBLE (-2550 3225);
FORCEPROP 0 LAST ROOM CPU0
J 0
(-3200 3375);
DISPLAY 1.021277 (-3200 3375);
PAINT ORANGE (-3200 3375);
DISPLAY INVISIBLE (-3200 3375);
FORCEADD OFFPAGE..1
(-7600 2750);
FORCEPROP 2 LAST $XR0 103 
J 0
(-7852 2750);
DISPLAY 0.638298 (-7852 2750);
PAINT MONO (-7852 2750);
FORCEPROP 2 LAST CDS_LIB mstr_standard
J 0
(-7600 2750);
PAINT MONO (-7600 2750);
DISPLAY INVISIBLE (-7600 2750);
FORCEPROP 1 LAST OFFPAGE TRUE
J 0
(-7275 2625);
DISPLAY 0.872340 (-7275 2625);
PAINT GREEN (-7275 2625);
DISPLAY INVISIBLE (-7275 2625);
FORCEPROP 1 LAST COMMENT_BODY TRUE
J 0
(-7475 2650);
DISPLAY 0.872340 (-7475 2650);
PAINT GREEN (-7475 2650);
DISPLAY INVISIBLE (-7475 2650);
FORCEPROP 2 LAST PATH I5
J 0
(-7550 2825);
DISPLAY 1.021277 (-7550 2825);
PAINT ORANGE (-7550 2825);
DISPLAY INVISIBLE (-7550 2825);
FORCEADD OFFPAGE..1
(-7600 3350);
FORCEPROP 2 LAST $XR0 103 
J 0
(-7852 3350);
DISPLAY 0.638298 (-7852 3350);
PAINT MONO (-7852 3350);
FORCEPROP 2 LAST CDS_LIB mstr_standard
J 0
(-7600 3350);
PAINT MONO (-7600 3350);
DISPLAY INVISIBLE (-7600 3350);
FORCEPROP 1 LAST OFFPAGE TRUE
J 0
(-7275 3225);
DISPLAY 0.872340 (-7275 3225);
PAINT GREEN (-7275 3225);
DISPLAY INVISIBLE (-7275 3225);
FORCEPROP 1 LAST COMMENT_BODY TRUE
J 0
(-7475 3250);
DISPLAY 0.872340 (-7475 3250);
PAINT GREEN (-7475 3250);
DISPLAY INVISIBLE (-7475 3250);
FORCEPROP 2 LAST PATH I8
J 0
(-7850 3400);
DISPLAY 1.021277 (-7850 3400);
PAINT ORANGE (-7850 3400);
DISPLAY INVISIBLE (-7850 3400);
FORCEADD DESIGN_NOTE..1
(-3000 1825);
FORCEPROP 0 LAST L1 CPU SYMBOLS 1-30 ARE PRELIMINARY AND SUBJECT TO CHANGE
J 0
(-3200 1700);
DISPLAY 1.021277 (-3200 1700);
PAINT ORANGE (-3200 1700);
FORCEPROP 2 LAST CDS_LIB mstr_symbols
J 0
(-3000 1825);
PAINT ORANGE (-3000 1825);
DISPLAY INVISIBLE (-3000 1825);
FORCEPROP 1 LAST COMMENT_BODY TRUE
J 0
(-2975 1925);
DISPLAY 0.978723 (-2975 1925);
PAINT ORANGE (-2975 1925);
DISPLAY INVISIBLE (-2975 1925);
FORCEADD DESIGN_NOTE..1
(-8025 3925);
FORCEPROP 0 LAST L1 MCP CLK IS USED FOR DEBUG ONLY
J 0
(-8200 3800);
DISPLAY 1.021277 (-8200 3800);
PAINT ORANGE (-8200 3800);
FORCEPROP 2 LAST CDS_LIB mstr_symbols
J 0
(-8025 3925);
PAINT ORANGE (-8025 3925);
DISPLAY INVISIBLE (-8025 3925);
FORCEPROP 1 LAST COMMENT_BODY TRUE
J 0
(-8000 4025);
DISPLAY 0.978723 (-8000 4025);
PAINT ORANGE (-8000 4025);
DISPLAY INVISIBLE (-8000 4025);
FORCEADD DESIGN_NOTE..1
(-6475 1125);
FORCEPROP 0 LAST L1 CPU SYMBOLS 1-30 ARE PRELIMINARY AND SUBJECT TO CHANGE
J 0
(-6675 1000);
DISPLAY 1.021277 (-6675 1000);
PAINT ORANGE (-6675 1000);
FORCEPROP 2 LAST CDS_LIB mstr_symbols
J 0
(-6475 1125);
PAINT ORANGE (-6475 1125);
DISPLAY INVISIBLE (-6475 1125);
FORCEPROP 1 LAST COMMENT_BODY TRUE
J 0
(-6450 1225);
DISPLAY 0.978723 (-6450 1225);
PAINT ORANGE (-6450 1225);
DISPLAY INVISIBLE (-6450 1225);
FORCEADD INTEL_CORP_BPAGE..1
(-425 -50);
FORCEPROP 1 LAST CDS_CON_LAST_MODIFIED Tue Dec 01 11:51:22 2015
J 0
(-1850 275);
DISPLAY 1.340426 (-1850 275);
PAINT GREEN (-1850 275);
DISPLAY INVISIBLE (-1850 275);
FORCEPROP 1 LAST CUSTOM_TXT_CDS <CURRENT_DESIGN_SHEET> OF <TOTAL_DESIGN_SHEETS>
J 0
(-925 -25);
PAINT GREEN (-925 -25);
FORCEPROP 1 LAST CUSTOM_TXT_CDS <CON_LAST_MODIFIED>
J 0
(-2350 300);
PAINT GREEN (-2350 300);
FORCEPROP 2 LAST CUSTOM_TXT_CDS <XR_PAGE_TITLE>
J 0
(-8315 5200);
DISPLAY 0.638298 (-8315 5200);
PAINT PINK (-8315 5200);
DISPLAY INVISIBLE (-8315 5200);
FORCEPROP 1 LAST SCH_ADDRESS3 Santa Clara, CA 95052-8119
J 0
(-4400 -25);
DISPLAY 0.617021 (-4400 -25);
PAINT GREEN (-4400 -25);
FORCEPROP 1 LAST SCH_ADDRESS2 P.O. BOX 58119
J 0
(-4400 25);
DISPLAY 0.617021 (-4400 25);
PAINT GREEN (-4400 25);
FORCEPROP 1 LAST SCH_ADDRESS1 2200 Mission College Blvd.
J 0
(-4400 75);
DISPLAY 0.617021 (-4400 75);
PAINT GREEN (-4400 75);
FORCEPROP 1 LAST SCH_TITLE SKYLAKE - SKT0 - 16 OF 21
J 0
(-8375 0);
DISPLAY 1.212766 (-8375 0);
PAINT GREEN (-8375 0);
FORCEPROP 1 LAST SCH_NUMBER H4694802
J 0
(-1725 100);
DISPLAY 1.212766 (-1725 100);
PAINT YELLOW (-1725 100);
FORCEPROP 1 LAST SCH_DEPT BESD
J 1
(-4875 50);
DISPLAY 1.212766 (-4875 50);
PAINT YELLOW (-4875 50);
FORCEPROP 1 LAST SCH_REV 2.420
J 0
(-675 100);
DISPLAY 0.978723 (-675 100);
PAINT YELLOW (-675 100);
FORCEPROP 2 LAST PAGE_BORDER TRUE
J 0
(-8315 5200);
DISPLAY 0.851064 (-8315 5200);
PAINT PINK (-8315 5200);
DISPLAY INVISIBLE (-8315 5200);
FORCEPROP 2 LAST CDS_LIB mstr_symbols
J 0
(-425 -50);
PAINT ORANGE (-425 -50);
DISPLAY INVISIBLE (-425 -50);
FORCEPROP 1 LAST COMMENT_BODY TRUE
J 0
(-413 -38);
DISPLAY 0.638298 (-413 -38);
PAINT GREEN (-413 -38);
DISPLAY INVISIBLE (-413 -38);
FORCEPROP 2 LAST CDS_XR_PAGE_TITLE CR-36 : @BASEBOARD_FAB2_LIB.BASEBOARD_FAB2(SCH_1):PAGE36
J 0
(-8315 5200);
DISPLAY 0.638298 (-8315 5200);
PAINT PINK (-8315 5200);
DISPLAY INVISIBLE (-8315 5200);
WIRE 16 -1 (-5475 1950)(-4500 1950);
WIRE 16 -1 (-4500 1950)(-4500 2000);
WIRE 16 -1 (-5475 2000)(-4500 2000);
WIRE 16 -1 (-4500 2000)(-4500 2150);
WIRE 16 -1 (-5475 2150)(-4500 2150);
WIRE 16 -1 (-4500 2150)(-4500 2250);
WIRE 16 -1 (-5475 2250)(-4500 2250);
WIRE 16 -1 (-4500 2250)(-4500 2450);
WIRE 16 -1 (-5475 2450)(-4500 2450);
WIRE 16 -1 (-4500 2450)(-4500 2500);
WIRE 16 -1 (-5475 2500)(-4500 2500);
WIRE 16 -1 (-4500 2500)(-4500 2550);
WIRE 16 -1 (-5475 2550)(-4500 2550);
WIRE 16 -1 (-4500 2550)(-4500 2700);
WIRE 16 -1 (-5475 2700)(-4500 2700);
WIRE 16 -1 (-4500 2700)(-4500 2800);
WIRE 16 -1 (-5475 2800)(-4500 2800);
WIRE 16 -1 (-4500 2800)(-4500 2850);
WIRE 16 -1 (-5475 2850)(-4500 2850);
WIRE 16 -1 (-4500 2850)(-4500 2950);
WIRE 16 -1 (-5475 2950)(-4500 2950);
WIRE 16 -1 (-4500 2950)(-4500 3100);
WIRE 16 -1 (-5475 3100)(-4500 3100);
WIRE 16 -1 (-4500 3100)(-4500 3150);
WIRE 16 -1 (-5475 3150)(-4500 3150);
WIRE 16 -1 (-4500 3150)(-4500 3250);
WIRE 16 -1 (-5475 3250)(-4500 3250);
WIRE 16 -1 (-4500 3250)(-4500 3350);
WIRE 16 -1 (-5475 3350)(-4500 3350);
WIRE 16 -1 (-4500 3350)(-4500 3450);
WIRE 16 -1 (-5475 3450)(-4500 3450);
WIRE 16 -1 (-4500 3450)(-4500 3600);
WIRE 16 -1 (-5475 3600)(-4500 3600);
WIRE 16 -1 (-4500 3600)(-4500 3650);
WIRE 16 -1 (-5475 3650)(-4500 3650);
WIRE 16 -1 (-4500 3650)(-4500 3750);
WIRE 16 -1 (-1850 2425)(-1725 2425);
WIRE 16 -1 (-1725 2425)(-1725 2475);
WIRE 16 -1 (-1850 2475)(-1725 2475);
WIRE 16 -1 (-1725 2475)(-1725 2525);
WIRE 16 -1 (-1850 2525)(-1725 2525);
WIRE 16 -1 (-1725 2525)(-1725 2575);
WIRE 16 -1 (-1850 2575)(-1725 2575);
WIRE 16 -1 (-1725 2575)(-925 2575);
WIRE 16 -1 (-925 2325)(-925 2575);
WIRE 16 -1 (-925 2575)(-925 2650);
WIRE 16 -1 (-925 2175)(-925 2325);
WIRE 16 -1 (-1700 2325)(-925 2325);
WIRE 16 -1 (-1700 2275)(-1700 2325);
WIRE 16 -1 (-1850 2325)(-1700 2325);
WIRE 16 -1 (-1850 2175)(-925 2175);
WIRE 16 -1 (-1850 2275)(-1700 2275);
WIRE 16 -1 (-6675 1450)(-7850 1450);
WIRE 16 -1 (-7850 1450)(-7850 1500);
WIRE 16 -1 (-6675 1500)(-7850 1500);
WIRE 16 -1 (-7850 1500)(-7850 1550);
WIRE 16 -1 (-6675 1550)(-7850 1550);
WIRE 16 -1 (-7850 1550)(-7850 1600);
WIRE 16 -1 (-6675 1600)(-7850 1600);
WIRE 16 -1 (-7850 1600)(-7850 1650);
WIRE 16 -1 (-6675 1650)(-7850 1650);
WIRE 16 -1 (-7850 1650)(-7850 1700);
WIRE 16 -1 (-6675 1700)(-7850 1700);
WIRE 16 -1 (-7850 1700)(-7850 1750);
WIRE 16 -1 (-6675 1750)(-7850 1750);
WIRE 16 -1 (-7850 1750)(-7850 1800);
WIRE 16 -1 (-6675 1800)(-7850 1800);
WIRE 16 -1 (-7850 1800)(-7850 1850);
WIRE 16 -1 (-6675 1850)(-7850 1850);
WIRE 16 -1 (-7850 1850)(-7850 1900);
WIRE 16 -1 (-6675 1900)(-7850 1900);
WIRE 16 -1 (-7850 1900)(-7850 1950);
WIRE 16 -1 (-6675 1950)(-7850 1950);
WIRE 16 -1 (-7850 1950)(-7850 2000);
WIRE 16 -1 (-6675 2000)(-7850 2000);
WIRE 16 -1 (-7850 2000)(-7850 2050);
WIRE 16 -1 (-6675 2050)(-7850 2050);
WIRE 16 -1 (-7850 2050)(-7850 2100);
WIRE 16 -1 (-6675 2100)(-7850 2100);
WIRE 16 -1 (-7850 2100)(-7850 2150);
WIRE 16 -1 (-6675 2150)(-7850 2150);
WIRE 16 -1 (-7850 2150)(-7850 2200);
WIRE 16 -1 (-6675 2200)(-7850 2200);
WIRE 16 -1 (-7850 2200)(-7850 2250);
WIRE 16 -1 (-6675 2250)(-7850 2250);
WIRE 16 -1 (-7850 2250)(-7850 2300);
WIRE 16 -1 (-4800 3000)(-5475 3000);
FORCEPROP 2 LAST SIG_NAME TP_CPU0_RSVD_113
J 0
(-5342 3009);
DISPLAY 0.617021 (-5342 3009);
PAINT ORANGE (-5342 3009);
FORCEPROP 2 LASTPROP $XRERR UNIQUE?
J 0
(-4770 3000);
DISPLAY 0.638298 (-4770 3000);
PAINT MONO (-4770 3000);
DISPLAY INVISIBLE (-4770 3000);
WIRE 16 -1 (-7350 2300)(-6675 2300);
FORCEPROP 2 LAST SIG_NAME TP_CPU0_RSVD_144
J 0
(-7342 2309);
DISPLAY 0.617021 (-7342 2309);
PAINT ORANGE (-7342 2309);
FORCEPROP 2 LASTPROP $XRERR UNIQUE?
J 0
(-7590 2300);
DISPLAY 0.638298 (-7590 2300);
PAINT MONO (-7590 2300);
DISPLAY INVISIBLE (-7590 2300);
WIRE 16 -1 (-7350 2350)(-6675 2350);
FORCEPROP 2 LAST SIG_NAME TP_CPU0_RSVD_145
J 0
(-7342 2359);
DISPLAY 0.617021 (-7342 2359);
PAINT ORANGE (-7342 2359);
FORCEPROP 2 LASTPROP $XRERR UNIQUE?
J 0
(-7590 2350);
DISPLAY 0.638298 (-7590 2350);
PAINT MONO (-7590 2350);
DISPLAY INVISIBLE (-7590 2350);
WIRE 16 -1 (-7350 2400)(-6675 2400);
FORCEPROP 2 LAST SIG_NAME TP_CPU0_RSVD_146
J 0
(-7342 2409);
DISPLAY 0.617021 (-7342 2409);
PAINT ORANGE (-7342 2409);
FORCEPROP 2 LASTPROP $XRERR UNIQUE?
J 0
(-7590 2400);
DISPLAY 0.638298 (-7590 2400);
PAINT MONO (-7590 2400);
DISPLAY INVISIBLE (-7590 2400);
WIRE 16 -1 (-7350 2450)(-6675 2450);
FORCEPROP 2 LAST SIG_NAME TP_CPU0_RSVD_147
J 0
(-7342 2459);
DISPLAY 0.617021 (-7342 2459);
PAINT ORANGE (-7342 2459);
FORCEPROP 2 LASTPROP $XRERR UNIQUE?
J 0
(-7590 2450);
DISPLAY 0.638298 (-7590 2450);
PAINT MONO (-7590 2450);
DISPLAY INVISIBLE (-7590 2450);
WIRE 16 -1 (-7350 2500)(-6675 2500);
FORCEPROP 2 LAST SIG_NAME TP_CPU0_RSVD_148
J 0
(-7342 2509);
DISPLAY 0.617021 (-7342 2509);
PAINT ORANGE (-7342 2509);
FORCEPROP 2 LASTPROP $XRERR UNIQUE?
J 0
(-7590 2500);
DISPLAY 0.638298 (-7590 2500);
PAINT MONO (-7590 2500);
DISPLAY INVISIBLE (-7590 2500);
WIRE 16 -1 (-7350 2550)(-6675 2550);
FORCEPROP 2 LAST SIG_NAME TP_CPU0_RSVD_149
J 0
(-7342 2559);
DISPLAY 0.617021 (-7342 2559);
PAINT ORANGE (-7342 2559);
FORCEPROP 2 LASTPROP $XRERR UNIQUE?
J 0
(-7590 2550);
DISPLAY 0.638298 (-7590 2550);
PAINT MONO (-7590 2550);
DISPLAY INVISIBLE (-7590 2550);
WIRE 16 -1 (-7350 2600)(-6675 2600);
FORCEPROP 2 LAST SIG_NAME TP_CPU0_RSVD_150
J 0
(-7342 2609);
DISPLAY 0.617021 (-7342 2609);
PAINT ORANGE (-7342 2609);
FORCEPROP 2 LASTPROP $XRERR UNIQUE?
J 0
(-7590 2600);
DISPLAY 0.638298 (-7590 2600);
PAINT MONO (-7590 2600);
DISPLAY INVISIBLE (-7590 2600);
WIRE 16 -1 (-7350 2650)(-6675 2650);
FORCEPROP 2 LAST SIG_NAME TP_CPU0_RSVD_151
J 0
(-7342 2659);
DISPLAY 0.617021 (-7342 2659);
PAINT ORANGE (-7342 2659);
FORCEPROP 2 LASTPROP $XRERR UNIQUE?
J 0
(-7590 2650);
DISPLAY 0.638298 (-7590 2650);
PAINT MONO (-7590 2650);
DISPLAY INVISIBLE (-7590 2650);
WIRE 16 -1 (-7350 2700)(-6675 2700);
FORCEPROP 2 LAST SIG_NAME TP_CPU0_RSVD_152
J 0
(-7342 2709);
DISPLAY 0.617021 (-7342 2709);
PAINT ORANGE (-7342 2709);
FORCEPROP 2 LASTPROP $XRERR UNIQUE?
J 0
(-7590 2700);
DISPLAY 0.638298 (-7590 2700);
PAINT MONO (-7590 2700);
DISPLAY INVISIBLE (-7590 2700);
WIRE 16 -1 (-7350 2800)(-6675 2800);
FORCEPROP 2 LAST SIG_NAME TP_CPU0_RSVD_154
J 0
(-7342 2809);
DISPLAY 0.617021 (-7342 2809);
PAINT ORANGE (-7342 2809);
FORCEPROP 2 LASTPROP $XRERR UNIQUE?
J 0
(-7590 2800);
DISPLAY 0.638298 (-7590 2800);
PAINT MONO (-7590 2800);
DISPLAY INVISIBLE (-7590 2800);
WIRE 16 -1 (-7350 2850)(-6675 2850);
FORCEPROP 2 LAST SIG_NAME TP_CPU0_RSVD_155
J 0
(-7342 2859);
DISPLAY 0.617021 (-7342 2859);
PAINT ORANGE (-7342 2859);
FORCEPROP 2 LASTPROP $XRERR UNIQUE?
J 0
(-7590 2850);
DISPLAY 0.638298 (-7590 2850);
PAINT MONO (-7590 2850);
DISPLAY INVISIBLE (-7590 2850);
WIRE 16 -1 (-7350 2900)(-6675 2900);
FORCEPROP 2 LAST SIG_NAME TP_CPU0_RSVD_156
J 0
(-7342 2909);
DISPLAY 0.617021 (-7342 2909);
PAINT ORANGE (-7342 2909);
FORCEPROP 2 LASTPROP $XRERR UNIQUE?
J 0
(-7590 2900);
DISPLAY 0.638298 (-7590 2900);
PAINT MONO (-7590 2900);
DISPLAY INVISIBLE (-7590 2900);
WIRE 16 -1 (-7350 2950)(-6675 2950);
FORCEPROP 2 LAST SIG_NAME TP_CPU0_RSVD_157
J 0
(-7342 2959);
DISPLAY 0.617021 (-7342 2959);
PAINT ORANGE (-7342 2959);
FORCEPROP 2 LASTPROP $XRERR UNIQUE?
J 0
(-7590 2950);
DISPLAY 0.638298 (-7590 2950);
PAINT MONO (-7590 2950);
DISPLAY INVISIBLE (-7590 2950);
WIRE 16 -1 (-7350 3000)(-6675 3000);
FORCEPROP 2 LAST SIG_NAME TP_CPU0_RSVD_158
J 0
(-7342 3009);
DISPLAY 0.617021 (-7342 3009);
PAINT ORANGE (-7342 3009);
FORCEPROP 2 LASTPROP $XRERR UNIQUE?
J 0
(-7590 3000);
DISPLAY 0.638298 (-7590 3000);
PAINT MONO (-7590 3000);
DISPLAY INVISIBLE (-7590 3000);
WIRE 16 -1 (-7350 3050)(-6675 3050);
FORCEPROP 2 LAST SIG_NAME TP_CPU0_RSVD_159
J 0
(-7342 3059);
DISPLAY 0.617021 (-7342 3059);
PAINT ORANGE (-7342 3059);
FORCEPROP 2 LASTPROP $XRERR UNIQUE?
J 0
(-7590 3050);
DISPLAY 0.638298 (-7590 3050);
PAINT MONO (-7590 3050);
DISPLAY INVISIBLE (-7590 3050);
WIRE 16 -1 (-7350 3100)(-6675 3100);
FORCEPROP 2 LAST SIG_NAME TP_CPU0_RSVD_160
J 0
(-7342 3109);
DISPLAY 0.617021 (-7342 3109);
PAINT ORANGE (-7342 3109);
FORCEPROP 2 LASTPROP $XRERR UNIQUE?
J 0
(-7590 3100);
DISPLAY 0.638298 (-7590 3100);
PAINT MONO (-7590 3100);
DISPLAY INVISIBLE (-7590 3100);
WIRE 16 -1 (-7350 3150)(-6675 3150);
FORCEPROP 2 LAST SIG_NAME TP_CPU0_RSVD_161
J 0
(-7342 3159);
DISPLAY 0.617021 (-7342 3159);
PAINT ORANGE (-7342 3159);
FORCEPROP 2 LASTPROP $XRERR UNIQUE?
J 0
(-7590 3150);
DISPLAY 0.638298 (-7590 3150);
PAINT MONO (-7590 3150);
DISPLAY INVISIBLE (-7590 3150);
WIRE 16 -1 (-7350 3200)(-6675 3200);
FORCEPROP 2 LAST SIG_NAME TP_CPU0_RSVD_162
J 0
(-7342 3209);
DISPLAY 0.617021 (-7342 3209);
PAINT ORANGE (-7342 3209);
FORCEPROP 2 LASTPROP $XRERR UNIQUE?
J 0
(-7590 3200);
DISPLAY 0.638298 (-7590 3200);
PAINT MONO (-7590 3200);
DISPLAY INVISIBLE (-7590 3200);
WIRE 16 -1 (-7350 3250)(-6675 3250);
FORCEPROP 2 LAST SIG_NAME TP_CPU0_RSVD_163
J 0
(-7342 3259);
DISPLAY 0.617021 (-7342 3259);
PAINT ORANGE (-7342 3259);
FORCEPROP 2 LASTPROP $XRERR UNIQUE?
J 0
(-7590 3250);
DISPLAY 0.638298 (-7590 3250);
PAINT MONO (-7590 3250);
DISPLAY INVISIBLE (-7590 3250);
WIRE 16 -1 (-7350 3300)(-6675 3300);
FORCEPROP 2 LAST SIG_NAME TP_CPU0_RSVD_164
J 0
(-7342 3309);
DISPLAY 0.617021 (-7342 3309);
PAINT ORANGE (-7342 3309);
FORCEPROP 2 LASTPROP $XRERR UNIQUE?
J 0
(-7590 3300);
DISPLAY 0.638298 (-7590 3300);
PAINT MONO (-7590 3300);
DISPLAY INVISIBLE (-7590 3300);
WIRE 16 -1 (-7350 3400)(-6675 3400);
FORCEPROP 2 LAST SIG_NAME TP_CPU0_RSVD_166
J 0
(-7342 3409);
DISPLAY 0.617021 (-7342 3409);
PAINT ORANGE (-7342 3409);
FORCEPROP 2 LASTPROP $XRERR UNIQUE?
J 0
(-7590 3400);
DISPLAY 0.638298 (-7590 3400);
PAINT MONO (-7590 3400);
DISPLAY INVISIBLE (-7590 3400);
WIRE 16 -1 (-7350 3450)(-6675 3450);
FORCEPROP 2 LAST SIG_NAME TP_CPU0_RSVD_167
J 0
(-7342 3459);
DISPLAY 0.617021 (-7342 3459);
PAINT ORANGE (-7342 3459);
FORCEPROP 2 LASTPROP $XRERR UNIQUE?
J 0
(-7590 3450);
DISPLAY 0.638298 (-7590 3450);
PAINT MONO (-7590 3450);
DISPLAY INVISIBLE (-7590 3450);
WIRE 16 -1 (-7350 3500)(-6675 3500);
FORCEPROP 2 LAST SIG_NAME TP_CPU0_RSVD_168
J 0
(-7342 3509);
DISPLAY 0.617021 (-7342 3509);
PAINT ORANGE (-7342 3509);
FORCEPROP 2 LASTPROP $XRERR UNIQUE?
J 0
(-7590 3500);
DISPLAY 0.638298 (-7590 3500);
PAINT MONO (-7590 3500);
DISPLAY INVISIBLE (-7590 3500);
WIRE 16 -1 (-7350 3550)(-6675 3550);
FORCEPROP 2 LAST SIG_NAME TP_CPU0_RSVD_169
J 0
(-7342 3559);
DISPLAY 0.617021 (-7342 3559);
PAINT ORANGE (-7342 3559);
FORCEPROP 2 LASTPROP $XRERR UNIQUE?
J 0
(-7590 3550);
DISPLAY 0.638298 (-7590 3550);
PAINT MONO (-7590 3550);
DISPLAY INVISIBLE (-7590 3550);
WIRE 16 -1 (-7350 3600)(-6675 3600);
FORCEPROP 2 LAST SIG_NAME TP_CPU0_RSVD_170
J 0
(-7342 3609);
DISPLAY 0.617021 (-7342 3609);
PAINT ORANGE (-7342 3609);
FORCEPROP 2 LASTPROP $XRERR UNIQUE?
J 0
(-7590 3600);
DISPLAY 0.638298 (-7590 3600);
PAINT MONO (-7590 3600);
DISPLAY INVISIBLE (-7590 3600);
WIRE 16 -1 (-7350 3650)(-6675 3650);
FORCEPROP 2 LAST SIG_NAME TP_CPU0_RSVD_171
J 0
(-7342 3659);
DISPLAY 0.617021 (-7342 3659);
PAINT ORANGE (-7342 3659);
FORCEPROP 2 LASTPROP $XRERR UNIQUE?
J 0
(-7590 3650);
DISPLAY 0.638298 (-7590 3650);
PAINT MONO (-7590 3650);
DISPLAY INVISIBLE (-7590 3650);
WIRE 16 -1 (-7550 2750)(-6675 2750);
FORCEPROP 2 LAST SIG_NAME CLK_100M_CPU0_RC_REFCLK1_DP
J 0
(-7492 2759);
DISPLAY 0.617021 (-7492 2759);
PAINT ORANGE (-7492 2759);
WIRE 16 -1 (-7550 3350)(-6675 3350);
FORCEPROP 2 LAST SIG_NAME CLK_100M_CPU0_RC_REFCLK1_DN
J 0
(-7517 3359);
DISPLAY 0.617021 (-7517 3359);
PAINT ORANGE (-7517 3359);
WIRE 16 -1 (-4800 1900)(-5475 1900);
FORCEPROP 2 LAST SIG_NAME TP_CPU0_RSVD_255
J 0
(-5342 1909);
DISPLAY 0.617021 (-5342 1909);
PAINT ORANGE (-5342 1909);
FORCEPROP 2 LASTPROP $XRERR UNIQUE?
J 0
(-4770 1900);
DISPLAY 0.638298 (-4770 1900);
PAINT MONO (-4770 1900);
DISPLAY INVISIBLE (-4770 1900);
WIRE 16 -1 (-5475 2050)(-4800 2050);
FORCEPROP 2 LAST SIG_NAME TP_CPU0_RSVD_94
J 0
(-5342 2059);
DISPLAY 0.617021 (-5342 2059);
PAINT ORANGE (-5342 2059);
FORCEPROP 2 LASTPROP $XRERR UNIQUE?
J 0
(-4770 2050);
DISPLAY 0.638298 (-4770 2050);
PAINT MONO (-4770 2050);
DISPLAY INVISIBLE (-4770 2050);
WIRE 16 -1 (-4800 2100)(-5475 2100);
FORCEPROP 2 LAST SIG_NAME TP_CPU0_RSVD_95
J 0
(-5342 2109);
DISPLAY 0.617021 (-5342 2109);
PAINT ORANGE (-5342 2109);
FORCEPROP 2 LASTPROP $XRERR UNIQUE?
J 0
(-4770 2100);
DISPLAY 0.638298 (-4770 2100);
PAINT MONO (-4770 2100);
DISPLAY INVISIBLE (-4770 2100);
WIRE 16 -1 (-4800 2200)(-5475 2200);
FORCEPROP 2 LAST SIG_NAME TP_CPU0_RSVD_97
J 0
(-5342 2209);
DISPLAY 0.617021 (-5342 2209);
PAINT ORANGE (-5342 2209);
FORCEPROP 2 LASTPROP $XRERR UNIQUE?
J 0
(-4770 2200);
DISPLAY 0.638298 (-4770 2200);
PAINT MONO (-4770 2200);
DISPLAY INVISIBLE (-4770 2200);
WIRE 16 -1 (-4800 2300)(-5475 2300);
FORCEPROP 2 LAST SIG_NAME TP_CPU0_RSVD_99
J 0
(-5342 2309);
DISPLAY 0.617021 (-5342 2309);
PAINT ORANGE (-5342 2309);
FORCEPROP 2 LASTPROP $XRERR UNIQUE?
J 0
(-4770 2300);
DISPLAY 0.638298 (-4770 2300);
PAINT MONO (-4770 2300);
DISPLAY INVISIBLE (-4770 2300);
WIRE 16 -1 (-4800 2350)(-5475 2350);
FORCEPROP 2 LAST SIG_NAME TP_CPU0_RSVD_100
J 0
(-5342 2359);
DISPLAY 0.617021 (-5342 2359);
PAINT ORANGE (-5342 2359);
FORCEPROP 2 LASTPROP $XRERR UNIQUE?
J 0
(-4770 2350);
DISPLAY 0.638298 (-4770 2350);
PAINT MONO (-4770 2350);
DISPLAY INVISIBLE (-4770 2350);
WIRE 16 -1 (-4800 2400)(-5475 2400);
FORCEPROP 2 LAST SIG_NAME TP_CPU0_RSVD_101
J 0
(-5342 2409);
DISPLAY 0.617021 (-5342 2409);
PAINT ORANGE (-5342 2409);
FORCEPROP 2 LASTPROP $XRERR UNIQUE?
J 0
(-4770 2400);
DISPLAY 0.638298 (-4770 2400);
PAINT MONO (-4770 2400);
DISPLAY INVISIBLE (-4770 2400);
WIRE 16 -1 (-4800 2600)(-5475 2600);
FORCEPROP 2 LAST SIG_NAME TP_CPU0_RSVD_105
J 0
(-5342 2609);
DISPLAY 0.617021 (-5342 2609);
PAINT ORANGE (-5342 2609);
FORCEPROP 2 LASTPROP $XRERR UNIQUE?
J 0
(-4770 2600);
DISPLAY 0.638298 (-4770 2600);
PAINT MONO (-4770 2600);
DISPLAY INVISIBLE (-4770 2600);
WIRE 16 -1 (-4800 2650)(-5475 2650);
FORCEPROP 2 LAST SIG_NAME TP_CPU0_RSVD_106
J 0
(-5342 2659);
DISPLAY 0.617021 (-5342 2659);
PAINT ORANGE (-5342 2659);
FORCEPROP 2 LASTPROP $XRERR UNIQUE?
J 0
(-4770 2650);
DISPLAY 0.638298 (-4770 2650);
PAINT MONO (-4770 2650);
DISPLAY INVISIBLE (-4770 2650);
WIRE 16 -1 (-4800 2750)(-5475 2750);
FORCEPROP 2 LAST SIG_NAME TP_CPU0_RSVD_108
J 0
(-5342 2759);
DISPLAY 0.617021 (-5342 2759);
PAINT ORANGE (-5342 2759);
FORCEPROP 2 LASTPROP $XRERR UNIQUE?
J 0
(-4770 2750);
DISPLAY 0.638298 (-4770 2750);
PAINT MONO (-4770 2750);
DISPLAY INVISIBLE (-4770 2750);
WIRE 16 -1 (-4800 2900)(-5475 2900);
FORCEPROP 2 LAST SIG_NAME TP_CPU0_RSVD_111
J 0
(-5342 2909);
DISPLAY 0.617021 (-5342 2909);
PAINT ORANGE (-5342 2909);
FORCEPROP 2 LASTPROP $XRERR UNIQUE?
J 0
(-4770 2900);
DISPLAY 0.638298 (-4770 2900);
PAINT MONO (-4770 2900);
DISPLAY INVISIBLE (-4770 2900);
WIRE 16 -1 (-4800 3050)(-5475 3050);
FORCEPROP 2 LAST SIG_NAME TP_CPU0_RSVD_114
J 0
(-5342 3059);
DISPLAY 0.617021 (-5342 3059);
PAINT ORANGE (-5342 3059);
FORCEPROP 2 LASTPROP $XRERR UNIQUE?
J 0
(-4770 3050);
DISPLAY 0.638298 (-4770 3050);
PAINT MONO (-4770 3050);
DISPLAY INVISIBLE (-4770 3050);
WIRE 16 -1 (-4800 3200)(-5475 3200);
FORCEPROP 2 LAST SIG_NAME TP_CPU0_RSVD_117
J 0
(-5342 3209);
DISPLAY 0.617021 (-5342 3209);
PAINT ORANGE (-5342 3209);
FORCEPROP 2 LASTPROP $XRERR UNIQUE?
J 0
(-4770 3200);
DISPLAY 0.638298 (-4770 3200);
PAINT MONO (-4770 3200);
DISPLAY INVISIBLE (-4770 3200);
WIRE 16 -1 (-5475 3300)(-4800 3300);
FORCEPROP 2 LAST SIG_NAME TP_CPU0_RSVD_119
J 0
(-5342 3309);
DISPLAY 0.617021 (-5342 3309);
PAINT ORANGE (-5342 3309);
FORCEPROP 2 LASTPROP $XRERR UNIQUE?
J 0
(-4770 3300);
DISPLAY 0.638298 (-4770 3300);
PAINT MONO (-4770 3300);
DISPLAY INVISIBLE (-4770 3300);
WIRE 16 -1 (-5475 3400)(-4800 3400);
FORCEPROP 2 LAST SIG_NAME TP_CPU0_RSVD_121
J 0
(-5342 3409);
DISPLAY 0.617021 (-5342 3409);
PAINT ORANGE (-5342 3409);
FORCEPROP 2 LASTPROP $XRERR UNIQUE?
J 0
(-4770 3400);
DISPLAY 0.638298 (-4770 3400);
PAINT MONO (-4770 3400);
DISPLAY INVISIBLE (-4770 3400);
WIRE 16 -1 (-4800 3500)(-5475 3500);
FORCEPROP 2 LAST SIG_NAME TP_CPU0_RSVD_123
J 0
(-5342 3509);
DISPLAY 0.617021 (-5342 3509);
PAINT ORANGE (-5342 3509);
FORCEPROP 2 LASTPROP $XRERR UNIQUE?
J 0
(-4770 3500);
DISPLAY 0.638298 (-4770 3500);
PAINT MONO (-4770 3500);
DISPLAY INVISIBLE (-4770 3500);
WIRE 16 -1 (-4800 3550)(-5475 3550);
FORCEPROP 2 LAST SIG_NAME TP_CPU0_RSVD_124
J 0
(-5342 3559);
DISPLAY 0.617021 (-5342 3559);
PAINT ORANGE (-5342 3559);
FORCEPROP 2 LASTPROP $XRERR UNIQUE?
J 0
(-4770 3550);
DISPLAY 0.638298 (-4770 3550);
PAINT MONO (-4770 3550);
DISPLAY INVISIBLE (-4770 3550);
WIRE 16 -1 (-1175 2875)(-1850 2875);
FORCEPROP 2 LAST SIG_NAME TP_CPU0_TEST_9
J 0
(-1700 2885);
DISPLAY 0.617021 (-1700 2885);
PAINT ORANGE (-1700 2885);
FORCEPROP 2 LASTPROP $XRERR UNIQUE?
J 0
(-1145 2875);
DISPLAY 0.638298 (-1145 2875);
PAINT MONO (-1145 2875);
DISPLAY INVISIBLE (-1145 2875);
WIRE 16 -1 (-1175 2925)(-1850 2925);
FORCEPROP 2 LAST SIG_NAME TP_CPU0_TEST_8
J 0
(-1700 2935);
DISPLAY 0.617021 (-1700 2935);
PAINT ORANGE (-1700 2935);
FORCEPROP 2 LASTPROP $XRERR UNIQUE?
J 0
(-1145 2925);
DISPLAY 0.638298 (-1145 2925);
PAINT MONO (-1145 2925);
DISPLAY INVISIBLE (-1145 2925);
WIRE 16 -1 (-1850 2975)(-1175 2975);
FORCEPROP 2 LAST SIG_NAME TP_CPU0_TEST_7
J 0
(-1700 2985);
DISPLAY 0.617021 (-1700 2985);
PAINT ORANGE (-1700 2985);
FORCEPROP 2 LASTPROP $XRERR UNIQUE?
J 0
(-1145 2975);
DISPLAY 0.638298 (-1145 2975);
PAINT MONO (-1145 2975);
DISPLAY INVISIBLE (-1145 2975);
WIRE 16 -1 (-1175 3025)(-1850 3025);
FORCEPROP 2 LAST SIG_NAME TP_CPU0_TEST_6
J 0
(-1700 3035);
DISPLAY 0.617021 (-1700 3035);
PAINT ORANGE (-1700 3035);
FORCEPROP 2 LASTPROP $XRERR UNIQUE?
J 0
(-1145 3025);
DISPLAY 0.638298 (-1145 3025);
PAINT MONO (-1145 3025);
DISPLAY INVISIBLE (-1145 3025);
WIRE 16 -1 (-1175 2825)(-1850 2825);
FORCEPROP 2 LAST SIG_NAME TP_CPU0_TEST_10
J 0
(-1700 2835);
DISPLAY 0.617021 (-1700 2835);
PAINT ORANGE (-1700 2835);
FORCEPROP 2 LASTPROP $XRERR UNIQUE?
J 0
(-1145 2825);
DISPLAY 0.638298 (-1145 2825);
PAINT MONO (-1145 2825);
DISPLAY INVISIBLE (-1145 2825);
WIRE 16 -1 (-1175 2225)(-1850 2225);
FORCEPROP 2 LAST SIG_NAME TP_CPU0_RSVD_82
J 0
(-1700 2235);
DISPLAY 0.617021 (-1700 2235);
PAINT ORANGE (-1700 2235);
FORCEPROP 2 LASTPROP $XRERR UNIQUE?
J 0
(-1145 2225);
DISPLAY 0.638298 (-1145 2225);
PAINT MONO (-1145 2225);
DISPLAY INVISIBLE (-1145 2225);
WIRE 16 -1 (-1850 2375)(-1175 2375);
FORCEPROP 2 LAST SIG_NAME TP_CPU0_RSVD_85
J 0
(-1700 2385);
DISPLAY 0.617021 (-1700 2385);
PAINT ORANGE (-1700 2385);
FORCEPROP 2 LASTPROP $XRERR UNIQUE?
J 0
(-1145 2375);
DISPLAY 0.638298 (-1145 2375);
PAINT MONO (-1145 2375);
DISPLAY INVISIBLE (-1145 2375);
WIRE 16 -1 (-1175 2675)(-1850 2675);
FORCEPROP 2 LAST SIG_NAME TP_CPU0_RSVD_90
J 0
(-1700 2685);
DISPLAY 0.617021 (-1700 2685);
PAINT ORANGE (-1700 2685);
FORCEPROP 2 LASTPROP $XRERR UNIQUE?
J 0
(-1145 2675);
DISPLAY 0.638298 (-1145 2675);
PAINT MONO (-1145 2675);
DISPLAY INVISIBLE (-1145 2675);
WIRE 16 -1 (-1175 2725)(-1850 2725);
FORCEPROP 2 LAST SIG_NAME TP_CPU0_RSVD_91
J 0
(-1700 2735);
DISPLAY 0.617021 (-1700 2735);
PAINT ORANGE (-1700 2735);
FORCEPROP 2 LASTPROP $XRERR UNIQUE?
J 0
(-1145 2725);
DISPLAY 0.638298 (-1145 2725);
PAINT MONO (-1145 2725);
DISPLAY INVISIBLE (-1145 2725);
DOT 1 (-7850 1950);
DOT 1 (-7850 1850);
DOT 1 (-7850 1500);
DOT 1 (-7850 1550);
DOT 1 (-7850 1600);
DOT 1 (-7850 1650);
DOT 1 (-7850 1700);
DOT 1 (-7850 1750);
DOT 1 (-7850 1800);
DOT 1 (-7850 1900);
DOT 1 (-7850 2000);
DOT 1 (-7850 2050);
DOT 1 (-7850 2100);
DOT 1 (-7850 2150);
DOT 1 (-7850 2200);
DOT 1 (-7850 2250);
DOT 1 (-4500 3250);
DOT 1 (-4500 2000);
DOT 1 (-4500 2150);
DOT 1 (-4500 2250);
DOT 1 (-4500 2450);
DOT 1 (-4500 2500);
DOT 1 (-4500 2550);
DOT 1 (-4500 2700);
DOT 1 (-4500 2800);
DOT 1 (-4500 2850);
DOT 1 (-4500 2950);
DOT 1 (-4500 3100);
DOT 1 (-4500 3150);
DOT 1 (-4500 3350);
DOT 1 (-4500 3450);
DOT 1 (-4500 3600);
DOT 1 (-4500 3650);
DOT 1 (-925 2325);
DOT 1 (-925 2575);
DOT 1 (-1700 2325);
DOT 1 (-1725 2475);
DOT 1 (-1725 2525);
DOT 1 (-1725 2575);
FORCENOTE
BOM_COST=PROC_SOCKET
(-8300 250) 0;
DISPLAY LEFT (-8300 250);
DISPLAY 1.723404 (-8300 250);
PAINT PURPLE (-8300 250);
FORCENOTE
ROOM=CPU0
(-8275 375) 0;
DISPLAY LEFT (-8275 375);
DISPLAY 1.723404 (-8275 375);
PAINT PURPLE (-8275 375);
QUIT
